(kicad_pcb
	(version 20241229)
	(generator "pcbnew")
	(generator_version "9.0")
	(general
		(thickness 1.6296)
		(legacy_teardrops no)
	)
	(paper "A3")
	(title_block
		(title "Thunderbolt to 10GbE adapter")
		(date "2026-04-21")
		(rev "1.1.0")
		(company "Antmicro Ltd")
		(comment 1 "www.antmicro.com")
		(comment 9 "footprints 155-158 of 703")
	)
	(layers
		(0 "F.Cu" signal)
		(4 "In1.Cu" signal)
		(6 "In2.Cu" signal)
		(8 "In3.Cu" signal)
		(10 "In4.Cu" signal)
		(12 "In5.Cu" signal)
		(14 "In6.Cu" signal)
		(2 "B.Cu" signal)
		(9 "F.Adhes" user "F.Adhesive")
		(11 "B.Adhes" user "B.Adhesive")
		(13 "F.Paste" user)
		(15 "B.Paste" user)
		(5 "F.SilkS" user "F.Silkscreen")
		(7 "B.SilkS" user "B.Silkscreen")
		(1 "F.Mask" user)
		(3 "B.Mask" user)
		(17 "Dwgs.User" user "User.Drawings")
		(19 "Cmts.User" user "User.Comments")
		(21 "Eco1.User" user "User.Eco1")
		(23 "Eco2.User" user "User.Eco2")
		(25 "Edge.Cuts" user)
		(27 "Margin" user)
		(31 "F.CrtYd" user "F.Courtyard")
		(29 "B.CrtYd" user "B.Courtyard")
		(35 "F.Fab" user)
		(33 "B.Fab" user)
	)
	(footprint "antmicro-footprints:SOIC-8_3.9x4.9x1.75mm_P1.27mm"
		(layer "F.Cu")
		(at 147.8 122.2 90)
		(property "Reference" "U7"
			(at 4.7 4 90)
			(layer "F.SilkS")
			(effects
				(font
					(size 0.7 0.7)
					(thickness 0.15)
				)
				(justify left bottom)
			)
		)
		(property "Value" "MX25L8006EM1I-12G"
			(at 0 3.65 90)
			(layer "F.Fab")
			(effects
				(font
					(size 0.7 0.7)
					(thickness 0.15)
				)
				(justify left bottom)
			)
		)
		(property "Datasheet" "https://www.macronix.com/Lists/Datasheet/Attachments/8680/MX25L8006E,%203V,%208Mb,%20v1.6.pdf"
			(at 0 0 90)
			(layer "F.Fab")
			(hide yes)
			(effects
				(font
					(size 1.27 1.27)
					(thickness 0.15)
				)
			)
		)
		(property "Description" "FLASH - NOR Memory IC 8Mbit SPI 86 MHz 8-SOP"
			(at 0 0 90)
			(layer "F.Fab")
			(hide yes)
			(effects
				(font
					(size 1.27 1.27)
					(thickness 0.15)
				)
			)
		)
		(property "MPN" "MX25L8006EM1I-12G"
			(at 0 0 90)
			(unlocked yes)
			(layer "F.Fab")
			(hide yes)
			(effects
				(font
					(size 1 1)
					(thickness 0.15)
				)
			)
		)
		(property "Manufacturer" "Macronix"
			(at 0 0 90)
			(unlocked yes)
			(layer "F.Fab")
			(hide yes)
			(effects
				(font
					(size 1 1)
					(thickness 0.15)
				)
			)
		)
		(property "License" "Apache-2.0"
			(at 0 0 90)
			(unlocked yes)
			(layer "F.Fab")
			(hide yes)
			(effects
				(font
					(size 1 1)
					(thickness 0.15)
				)
			)
		)
		(property "Author" "Antmicro"
			(at 0 0 90)
			(unlocked yes)
			(layer "F.Fab")
			(hide yes)
			(effects
				(font
					(size 1 1)
					(thickness 0.15)
				)
			)
		)
		(sheetname "/TB flash memory/")
		(sheetfile "flash-memory.kicad_sch")
		(attr smd)
		(fp_line
			(start -1.95 -2.452)
			(end 1.95 -2.45)
			(stroke
				(width 0.15)
				(type solid)
			)
			(layer "F.SilkS")
		)
		(fp_line
			(start -1.95 2.45)
			(end 1.95 2.45)
			(stroke
				(width 0.15)
				(type solid)
			)
			(layer "F.SilkS")
		)
		(fp_circle
			(center -2.4 -2.45)
			(end -2.35 -2.4)
			(stroke
				(width 0.15)
				(type solid)
			)
			(fill yes)
			(layer "F.SilkS")
		)
		(fp_rect
			(start -3.625 -2.7)
			(end 3.625 2.7)
			(stroke
				(width 0.05)
				(type solid)
			)
			(fill no)
			(layer "F.CrtYd")
		)
		(fp_line
			(start 1.949 -2.452)
			(end 1.949 2.45)
			(stroke
				(width 0.15)
				(type solid)
			)
			(layer "F.Fab")
		)
		(fp_line
			(start -0.683 -2.452)
			(end 1.949 -2.452)
			(stroke
				(width 0.15)
				(type solid)
			)
			(layer "F.Fab")
		)
		(fp_line
			(start -1.95 -1.18)
			(end -0.683 -2.452)
			(stroke
				(width 0.15)
				(type solid)
			)
			(layer "F.Fab")
		)
		(fp_line
			(start 1.949 2.45)
			(end -1.95 2.45)
			(stroke
				(width 0.15)
				(type solid)
			)
			(layer "F.Fab")
		)
		(fp_line
			(start -1.95 2.45)
			(end -1.95 -1.18)
			(stroke
				(width 0.15)
				(type solid)
			)
			(layer "F.Fab")
		)
		(fp_text user "${REFERENCE}"
			(at -3.476 7.099 90)
			(layer "F.Fab")
			(effects
				(font
					(size 0.7 0.7)
					(thickness 0.15)
				)
				(justify left bottom)
			)
		)
		(fp_text user "Author: Antmicro"
			(at -3.476 6.099 90)
			(layer "F.Fab")
			(effects
				(font
					(size 0.7 0.7)
					(thickness 0.15)
				)
				(justify left bottom)
			)
		)
		(fp_text user "License: Apache-2.0"
			(at -3.476 5.099 90)
			(layer "F.Fab")
			(effects
				(font
					(size 0.7 0.7)
					(thickness 0.15)
				)
				(justify left bottom)
			)
		)
		(pad "1" smd roundrect
			(at -2.714 -1.905 180)
			(size 0.65 1.525)
			(layers "F.Cu" "F.Mask" "F.Paste")
			(roundrect_rratio 0.25)
			(net 359 "/PD and TB DC-DC/TB_FLASH.~{CE}")
			(pinfunction "~{CS}")
			(pintype "input")
		)
		(pad "2" smd roundrect
			(at -2.714 -0.635 180)
			(size 0.65 1.525)
			(layers "F.Cu" "F.Mask" "F.Paste")
			(roundrect_rratio 0.25)
			(net 357 "/PD and TB DC-DC/TB_FLASH.MISO")
			(pinfunction "SO/IO1")
			(pintype "input")
		)
		(pad "3" smd roundrect
			(at -2.714 0.632 180)
			(size 0.65 1.525)
			(layers "F.Cu" "F.Mask" "F.Paste")
			(roundrect_rratio 0.25)
			(net 358 "/TB flash memory/FLASH_WP")
			(pinfunction "~{WP}")
			(pintype "input")
		)
		(pad "4" smd roundrect
			(at -2.714 1.902 180)
			(size 0.65 1.525)
			(layers "F.Cu" "F.Mask" "F.Paste")
			(roundrect_rratio 0.25)
			(net 23 "GND")
			(pinfunction "GND")
			(pintype "power_in")
		)
		(pad "5" smd roundrect
			(at 2.712 1.902 180)
			(size 0.65 1.525)
			(layers "F.Cu" "F.Mask" "F.Paste")
			(roundrect_rratio 0.25)
			(net 398 "/PD and TB DC-DC/TB_FLASH.MOSI")
			(pinfunction "SI/IO0")
			(pintype "input")
		)
		(pad "6" smd roundrect
			(at 2.712 0.632 180)
			(size 0.65 1.525)
			(layers "F.Cu" "F.Mask" "F.Paste")
			(roundrect_rratio 0.25)
			(net 397 "/PD and TB DC-DC/TB_FLASH.CLK")
			(pinfunction "SCLK")
			(pintype "input")
		)
		(pad "7" smd roundrect
			(at 2.712 -0.635 180)
			(size 0.65 1.525)
			(layers "F.Cu" "F.Mask" "F.Paste")
			(roundrect_rratio 0.25)
			(net 370 "/TB flash memory/FLASH_HOLD")
			(pinfunction "~{HOLD}")
			(pintype "input")
		)
		(pad "8" smd roundrect
			(at 2.712 -1.905 180)
			(size 0.65 1.525)
			(layers "F.Cu" "F.Mask" "F.Paste")
			(roundrect_rratio 0.25)
			(net 57 "+3V3_TB")
			(pinfunction "VCC")
			(pintype "power_in")
		)
	)
	(footprint "antmicro-footprints:R_0402_1005Metric"
		(layer "F.Cu")
		(at 132.8 71.4 180)
		(descr "Resistor SMD 0402")
		(tags "resistor SMD 0402")
		(property "Reference" "R224"
			(at 0.8 2 180)
			(layer "F.SilkS")
			(effects
				(font
					(size 0.7 0.7)
					(thickness 0.15)
				)
				(justify left bottom)
			)
		)
		(property "Value" "R_10k_0402"
			(at -1.011843 1.772047 180)
			(layer "F.Fab")
			(effects
				(font
					(size 0.7 0.7)
					(thickness 0.15)
				)
				(justify left bottom)
			)
		)
		(property "Datasheet" "https://www.bourns.com/docs/product-datasheets/cr.pdf"
			(at 0 0 180)
			(layer "F.Fab")
			(hide yes)
			(effects
				(font
					(size 1.27 1.27)
					(thickness 0.15)
				)
			)
		)
		(property "Description" "SMD Chip Resistor, 10 kohm, ± 1%, 62.5 mW, 0402 [1005 Metric], Thick Film, General Purpose"
			(at 0 0 180)
			(layer "F.Fab")
			(hide yes)
			(effects
				(font
					(size 1.27 1.27)
					(thickness 0.15)
				)
			)
		)
		(property "MPN" "CR0402-FX-1002GLF"
			(at 0 0 180)
			(unlocked yes)
			(layer "F.Fab")
			(hide yes)
			(effects
				(font
					(size 1 1)
					(thickness 0.15)
				)
			)
		)
		(property "Manufacturer" "Bourns"
			(at 0 0 180)
			(unlocked yes)
			(layer "F.Fab")
			(hide yes)
			(effects
				(font
					(size 1 1)
					(thickness 0.15)
				)
			)
		)
		(property "License" "Apache-2.0"
			(at 0 0 180)
			(unlocked yes)
			(layer "F.Fab")
			(hide yes)
			(effects
				(font
					(size 1 1)
					(thickness 0.15)
				)
			)
		)
		(property "Author" "Antmicro"
			(at 0 0 180)
			(unlocked yes)
			(layer "F.Fab")
			(hide yes)
			(effects
				(font
					(size 1 1)
					(thickness 0.15)
				)
			)
		)
		(property "Val" "10k"
			(at 0 0 180)
			(unlocked yes)
			(layer "F.Fab")
			(hide yes)
			(effects
				(font
					(size 1 1)
					(thickness 0.15)
				)
			)
		)
		(property "Tolerance" "1%"
			(at 0 0 180)
			(unlocked yes)
			(layer "F.Fab")
			(hide yes)
			(effects
				(font
					(size 1 1)
					(thickness 0.15)
				)
			)
		)
		(sheetname "/X710 flash memory/")
		(sheetfile "flash_x710.kicad_sch")
		(attr smd)
		(fp_rect
			(start -0.925 -0.47)
			(end 0.925 0.47)
			(stroke
				(width 0.05)
				(type default)
			)
			(fill no)
			(layer "F.CrtYd")
		)
		(fp_rect
			(start -0.5 -0.25)
			(end 0.5 0.25)
			(stroke
				(width 0.15)
				(type solid)
			)
			(fill no)
			(layer "F.Fab")
		)
		(fp_text user "Author: Antmicro"
			(at -0.95 4.169 180)
			(layer "F.Fab")
			(effects
				(font
					(size 0.7 0.7)
					(thickness 0.15)
				)
				(justify left bottom)
			)
		)
		(fp_text user "License: Apache-2.0"
			(at -0.95 5.169 180)
			(layer "F.Fab")
			(effects
				(font
					(size 0.7 0.7)
					(thickness 0.15)
				)
				(justify left bottom)
			)
		)
		(fp_text user "${REFERENCE}"
			(at -0.95 3.168 180)
			(layer "F.Fab")
			(effects
				(font
					(size 0.7 0.7)
					(thickness 0.15)
				)
				(justify left bottom)
			)
		)
		(pad "1" smd roundrect
			(at -0.48 0 180)
			(size 0.59 0.64)
			(layers "F.Cu" "F.Mask" "F.Paste")
			(roundrect_rratio 0.25)
			(net 387 "/X710 flash memory/~{HOLD}")
			(pintype "passive")
		)
		(pad "2" smd roundrect
			(at 0.48 0 180)
			(size 0.59 0.64)
			(layers "F.Cu" "F.Mask" "F.Paste")
			(roundrect_rratio 0.25)
			(net 343 "/X710 flash memory/+3V3_FLASH")
			(pintype "passive")
		)
	)
	(footprint "antmicro-footprints:FB_0603_1608Metric"
		(layer "F.Cu")
		(at 148.755 97.374999 90)
		(property "Reference" "FB5"
			(at -19.625001 23.294999 90)
			(layer "F.SilkS")
			(effects
				(font
					(size 0.7 0.7)
					(thickness 0.15)
				)
			)
		)
		(property "Value" "FB_33Z_3A_Murata-BLM18PG_0603"
			(at 0 1.5 90)
			(layer "F.Fab")
			(effects
				(font
					(size 0.7 0.7)
					(thickness 0.15)
				)
				(justify left bottom)
			)
		)
		(property "Datasheet" "https://www.murata.com/products/productdata/8796737273886/QNFA9101.pdf?1649080818000"
			(at 0 0 90)
			(layer "F.Fab")
			(hide yes)
			(effects
				(font
					(size 1.27 1.27)
					(thickness 0.15)
				)
			)
		)
		(property "Description" "Ferrite Bead, 0603 [1608 Metric], 33 ohm, 3 A, BLM18PG, 0.025 ohm, ± 25%, DC power line"
			(at 0 0 90)
			(layer "F.Fab")
			(hide yes)
			(effects
				(font
					(size 1.27 1.27)
					(thickness 0.15)
				)
			)
		)
		(property "Val" "33Z/3A"
			(at 0 0 90)
			(unlocked yes)
			(layer "F.Fab")
			(hide yes)
			(effects
				(font
					(size 1 1)
					(thickness 0.15)
				)
			)
		)
		(property "MPN" "BLM18PG330SH1D"
			(at 0 0 90)
			(unlocked yes)
			(layer "F.Fab")
			(hide yes)
			(effects
				(font
					(size 1 1)
					(thickness 0.15)
				)
			)
		)
		(property "Manufacturer" "Murata"
			(at 0 0 90)
			(unlocked yes)
			(layer "F.Fab")
			(hide yes)
			(effects
				(font
					(size 1 1)
					(thickness 0.15)
				)
			)
		)
		(property "Current" ""
			(at 0 0 90)
			(unlocked yes)
			(layer "F.Fab")
			(hide yes)
			(effects
				(font
					(size 1 1)
					(thickness 0.15)
				)
			)
		)
		(property "Author" "Antmicro"
			(at 0 0 90)
			(unlocked yes)
			(layer "F.Fab")
			(hide yes)
			(effects
				(font
					(size 1 1)
					(thickness 0.15)
				)
			)
		)
		(property "License" "Apache-2.0"
			(at 0 0 90)
			(unlocked yes)
			(layer "F.Fab")
			(hide yes)
			(effects
				(font
					(size 1 1)
					(thickness 0.15)
				)
			)
		)
		(sheetname "/X710-AT2 power/")
		(sheetfile "x710-at2-power.kicad_sch")
		(attr smd)
		(fp_line
			(start -0.15 -0.4)
			(end 0.15 -0.4)
			(stroke
				(width 0.15)
				(type solid)
			)
			(layer "F.SilkS")
		)
		(fp_line
			(start -0.15 0.4)
			(end 0.15 0.4)
			(stroke
				(width 0.15)
				(type solid)
			)
			(layer "F.SilkS")
		)
		(fp_rect
			(start -1.25 -0.65)
			(end 1.25 0.65)
			(stroke
				(width 0.05)
				(type solid)
			)
			(fill no)
			(layer "F.CrtYd")
		)
		(fp_line
			(start 0.8 -0.408)
			(end -0.803 -0.408)
			(stroke
				(width 0.15)
				(type solid)
			)
			(layer "F.Fab")
		)
		(fp_line
			(start 0.8 -0.408)
			(end 0.8 0.406)
			(stroke
				(width 0.15)
				(type solid)
			)
			(layer "F.Fab")
		)
		(fp_line
			(start 0.8 0.406)
			(end -0.803 0.406)
			(stroke
				(width 0.15)
				(type solid)
			)
			(layer "F.Fab")
		)
		(fp_line
			(start -0.803 0.406)
			(end -0.803 -0.408)
			(stroke
				(width 0.15)
				(type solid)
			)
			(layer "F.Fab")
		)
		(fp_text user "Author: Antmicro"
			(at -1.653 3.162 90)
			(layer "F.Fab")
			(effects
				(font
					(size 0.7 0.7)
					(thickness 0.15)
				)
				(justify left bottom)
			)
		)
		(fp_text user "License: Apache-2.0"
			(at -1.653 5.9 90)
			(layer "F.Fab")
			(effects
				(font
					(size 0.7 0.7)
					(thickness 0.15)
				)
				(justify left bottom)
			)
		)
		(fp_text user "${REFERENCE}"
			(at -1.653 4.6 90)
			(layer "F.Fab")
			(effects
				(font
					(size 0.7 0.7)
					(thickness 0.15)
				)
				(justify left bottom)
			)
		)
		(pad "1" smd roundrect
			(at -0.7 0 90)
			(size 0.8 1)
			(layers "F.Cu" "F.Mask" "F.Paste")
			(roundrect_rratio 0.2)
			(net 18 "+1V88")
			(pintype "passive")
		)
		(pad "2" smd roundrect
			(at 0.7 0 90)
			(size 0.8 1)
			(layers "F.Cu" "F.Mask" "F.Paste")
			(roundrect_rratio 0.2)
			(net 10 "AVDDH")
			(pintype "passive")
		)
	)
	(footprint "antmicro-footprints:C_0402_1005Metric"
		(layer "F.Cu")
		(at 154.705001 98.574999 180)
		(descr "Capacitor SMD 0402")
		(tags "capacitor SMD 0402")
		(property "Reference" "C159"
			(at -23.294999 -19.625001 180)
			(layer "F.SilkS")
			(effects
				(font
					(size 0.7 0.7)
					(thickness 0.15)
				)
			)
		)
		(property "Value" "C_100n_0402"
			(at -1.022927 2.155213 180)
			(layer "F.Fab")
			(effects
				(font
					(size 0.7 0.7)
					(thickness 0.15)
				)
				(justify left bottom)
			)
		)
		(property "Datasheet" "https://www.murata.com/products/productdetail?partno=GRM155R61H104KE14%23"
			(at 0 0 180)
			(layer "F.Fab")
			(hide yes)
			(effects
				(font
					(size 1.27 1.27)
					(thickness 0.15)
				)
			)
		)
		(property "Description" "SMD Multilayer Ceramic Capacitor, 0.1 µF, 50 V, 0402 [1005 Metric], ± 10%, X5R, GRM Series"
			(at 0 0 180)
			(layer "F.Fab")
			(hide yes)
			(effects
				(font
					(size 1.27 1.27)
					(thickness 0.15)
				)
			)
		)
		(property "MPN" "GRM155R61H104KE14D"
			(at 0 0 180)
			(unlocked yes)
			(layer "F.Fab")
			(hide yes)
			(effects
				(font
					(size 1 1)
					(thickness 0.15)
				)
			)
		)
		(property "Val" "100n"
			(at 0 0 180)
			(unlocked yes)
			(layer "F.Fab")
			(hide yes)
			(effects
				(font
					(size 1 1)
					(thickness 0.15)
				)
			)
		)
		(property "Voltage" "50V"
			(at 0 0 180)
			(unlocked yes)
			(layer "F.Fab")
			(hide yes)
			(effects
				(font
					(size 1 1)
					(thickness 0.15)
				)
			)
		)
		(property "Dielectric" "X5R"
			(at 0 0 180)
			(unlocked yes)
			(layer "F.Fab")
			(hide yes)
			(effects
				(font
					(size 1 1)
					(thickness 0.15)
				)
			)
		)
		(property "Manufacturer" "Murata"
			(at 0 0 180)
			(unlocked yes)
			(layer "F.Fab")
			(hide yes)
			(effects
				(font
					(size 1 1)
					(thickness 0.15)
				)
			)
		)
		(property "License" "Apache-2.0"
			(at 0 0 180)
			(unlocked yes)
			(layer "F.Fab")
			(hide yes)
			(effects
				(font
					(size 1 1)
					(thickness 0.15)
				)
			)
		)
		(property "Author" "Antmicro"
			(at 0 0 180)
			(unlocked yes)
			(layer "F.Fab")
			(hide yes)
			(effects
				(font
					(size 1 1)
					(thickness 0.15)
				)
			)
		)
		(sheetname "/X710-AT2 power/")
		(sheetfile "x710-at2-power.kicad_sch")
		(attr smd)
		(fp_rect
			(start -0.925 -0.47)
			(end 0.925 0.47)
			(stroke
				(width 0.05)
				(type default)
			)
			(fill no)
			(layer "F.CrtYd")
		)
		(fp_line
			(start 0.504 0.248)
			(end -0.494 0.248)
			(stroke
				(width 0.15)
				(type solid)
			)
			(layer "F.Fab")
		)
		(fp_line
			(start 0.504 -0.25)
			(end 0.504 0.248)
			(stroke
				(width 0.15)
				(type solid)
			)
			(layer "F.Fab")
		)
		(fp_line
			(start -0.494 0.248)
			(end -0.494 -0.25)
			(stroke
				(width 0.15)
				(type solid)
			)
			(layer "F.Fab")
		)
		(fp_line
			(start -0.494 -0.25)
			(end 0.504 -0.25)
			(stroke
				(width 0.15)
				(type solid)
			)
			(layer "F.Fab")
		)
		(fp_text user "${REFERENCE}"
			(at -0.939 4.599 180)
			(layer "F.Fab")
			(effects
				(font
					(size 0.7 0.7)
					(thickness 0.15)
				)
				(justify left bottom)
			)
		)
		(fp_text user "Author: Antmicro"
			(at -0.939 3.399 180)
			(layer "F.Fab")
			(effects
				(font
					(size 0.7 0.7)
					(thickness 0.15)
				)
				(justify left bottom)
			)
		)
		(fp_text user "License: Apache-2.0"
			(at -0.939 5.799 180)
			(layer "F.Fab")
			(effects
				(font
					(size 0.7 0.7)
					(thickness 0.15)
				)
				(justify left bottom)
			)
		)
		(pad "1" smd roundrect
			(at -0.48 0 180)
			(size 0.59 0.64)
			(layers "F.Cu" "F.Mask" "F.Paste")
			(roundrect_rratio 0.25)
			(net 23 "GND")
			(pintype "passive")
		)
		(pad "2" smd roundrect
			(at 0.48 0 180)
			(size 0.59 0.64)
			(layers "F.Cu" "F.Mask" "F.Paste")
			(roundrect_rratio 0.25)
			(net 136 "+1V0")
			(pintype "passive")
		)
	)
)
